(kicad_pcb
	(version 20260206)
	(generator "pcbnew")
	(generator_version "10.0")
	(general
		(thickness 1.6)
		(legacy_teardrops no)
	)
	(paper "A4")
	(title_block
		(title "04192023_DAF0TMB3IC0_F0TG_MB_C_brd_V02_OCP.brd")
		(comment 1 "Grand Teton / footprints 5126-5131 of 8354")
	)
	(layers
		(0 "F.Cu" signal "TOP")
		(4 "In1.Cu" signal "GND")
		(6 "In2.Cu" signal "IN1")
		(8 "In3.Cu" signal "GND1")
		(10 "In4.Cu" signal "IN2")
		(12 "In5.Cu" signal "GND2")
		(14 "In6.Cu" signal "IN3")
		(16 "In7.Cu" signal "GND3")
		(18 "In8.Cu" signal "VCC")
		(20 "In9.Cu" signal "VCC1")
		(22 "In10.Cu" signal "GND4")
		(24 "In11.Cu" signal "IN4")
		(26 "In12.Cu" signal "GND5")
		(28 "In13.Cu" signal "IN5")
		(30 "In14.Cu" signal "GND6")
		(32 "In15.Cu" signal "IN6")
		(34 "In16.Cu" signal "GND7")
		(2 "B.Cu" signal "BOTTOM")
		(9 "F.Adhes" user "F.Adhesive")
		(11 "B.Adhes" user "B.Adhesive")
		(13 "F.Paste" user "Package Geometry/Pastemask Top")
		(15 "B.Paste" user "Package Geometry/Pastemask Bottom")
		(5 "F.SilkS" user "Ref Des/Silkscreen Top")
		(7 "B.SilkS" user "Ref Des/Silkscreen Bottom")
		(1 "F.Mask" user "Board Geometry/Soldermask Top")
		(3 "B.Mask" user "Board Geometry/Soldermask Bottom")
		(17 "Dwgs.User" user "User.Drawings")
		(19 "Cmts.User" user "User.Comments")
		(21 "Eco1.User" user "User.Eco1")
		(23 "Eco2.User" user "User.Eco2")
		(25 "Edge.Cuts" user "Board Geometry/Outline")
		(27 "Margin" user)
		(31 "F.CrtYd" user "Package Geometry/Place Bound Top")
		(29 "B.CrtYd" user "Package Geometry/Place Bound Bottom")
		(35 "F.Fab" user "Ref Des/Assembly Top")
		(33 "B.Fab" user "Ref Des/Assembly Bottom")
	)
	(footprint ""
		(layer "B.Cu")
		(at 445.888364 -194.89547 180)
		(property "Reference" "R1578"
			(at 0 0 0)
			(layer "B.SilkS")
			(hide yes)
			(effects
				(font
					(size 1.27 1.27)
				)
				(justify mirror)
			)
		)
		(property "Value" ""
			(at 0 0 0)
			(layer "B.Fab")
			(effects
				(font
					(size 1.27 1.27)
				)
				(justify mirror)
			)
		)
		(duplicate_pad_numbers_are_jumpers no)
		(fp_line
			(start 0.7874 0.4064)
			(end 0.7874 -0.4064)
			(stroke
				(width 0.1524)
				(type default)
			)
			(layer "B.SilkS")
		)
		(fp_line
			(start 0.7874 -0.4064)
			(end -0.7874 -0.4064)
			(stroke
				(width 0.1524)
				(type default)
			)
			(layer "B.SilkS")
		)
		(fp_line
			(start -0.7874 0.4064)
			(end 0.7874 0.4064)
			(stroke
				(width 0.1524)
				(type default)
			)
			(layer "B.SilkS")
		)
		(fp_line
			(start -0.7874 -0.4064)
			(end -0.7874 0.4064)
			(stroke
				(width 0.1524)
				(type default)
			)
			(layer "B.SilkS")
		)
		(fp_line
			(start 0.67945 0.3048)
			(end 0.67945 -0.305054)
			(stroke
				(width 0.1)
				(type default)
			)
			(layer "B.Fab")
		)
		(fp_line
			(start 0.67945 -0.305054)
			(end 0.12065 -0.305054)
			(stroke
				(width 0.1)
				(type default)
			)
			(layer "B.Fab")
		)
		(fp_line
			(start 0.12065 0.3048)
			(end 0.67945 0.3048)
			(stroke
				(width 0.1)
				(type default)
			)
			(layer "B.Fab")
		)
		(fp_line
			(start 0.12065 0.2794)
			(end 0.12065 0.3048)
			(stroke
				(width 0.1)
				(type default)
			)
			(layer "B.Fab")
		)
		(fp_line
			(start 0.12065 -0.2794)
			(end -0.12065 -0.2794)
			(stroke
				(width 0.1)
				(type default)
			)
			(layer "B.Fab")
		)
		(fp_line
			(start 0.12065 -0.305054)
			(end 0.12065 -0.2794)
			(stroke
				(width 0.1)
				(type default)
			)
			(layer "B.Fab")
		)
		(fp_line
			(start -0.120396 0.3048)
			(end -0.120396 0.2794)
			(stroke
				(width 0.1)
				(type default)
			)
			(layer "B.Fab")
		)
		(fp_line
			(start -0.120396 0.2794)
			(end 0.12065 0.2794)
			(stroke
				(width 0.1)
				(type default)
			)
			(layer "B.Fab")
		)
		(fp_line
			(start -0.12065 -0.2794)
			(end -0.12065 -0.3048)
			(stroke
				(width 0.1)
				(type default)
			)
			(layer "B.Fab")
		)
		(fp_line
			(start -0.12065 -0.3048)
			(end -0.67945 -0.3048)
			(stroke
				(width 0.1)
				(type default)
			)
			(layer "B.Fab")
		)
		(fp_line
			(start -0.67945 0.3048)
			(end -0.120396 0.3048)
			(stroke
				(width 0.1)
				(type default)
			)
			(layer "B.Fab")
		)
		(fp_line
			(start -0.67945 -0.3048)
			(end -0.67945 0.3048)
			(stroke
				(width 0.1)
				(type default)
			)
			(layer "B.Fab")
		)
		(pad "1" smd circle
			(at 0.40005 0)
			(size 0 0)
			(layers "B.Cu" "B.Mask" "B.Paste")
			(net "I3C_SPD_DDRGL_CPU0_SCL")
		)
		(pad "2" smd circle
			(at -0.40005 0)
			(size 0 0)
			(layers "B.Cu" "B.Mask" "B.Paste")
			(net "I3C_SPD_DDRK_CPU0_SCL")
		)
	)
	(footprint ""
		(layer "B.Cu")
		(at 122.861578 -261.93623)
		(property "Reference" "C2456"
			(at 0 0 0)
			(layer "B.SilkS")
			(hide yes)
			(effects
				(font
					(size 1.27 1.27)
				)
				(justify mirror)
			)
		)
		(property "Value" ""
			(at 0 0 0)
			(layer "B.Fab")
			(effects
				(font
					(size 1.27 1.27)
				)
				(justify mirror)
			)
		)
		(duplicate_pad_numbers_are_jumpers no)
		(fp_line
			(start -0.7874 -0.4064)
			(end -0.7874 0.4064)
			(stroke
				(width 0.1524)
				(type default)
			)
			(layer "B.SilkS")
		)
		(fp_line
			(start -0.7874 0.4064)
			(end 0.7874 0.4064)
			(stroke
				(width 0.1524)
				(type default)
			)
			(layer "B.SilkS")
		)
		(fp_line
			(start 0.7874 -0.4064)
			(end -0.7874 -0.4064)
			(stroke
				(width 0.1524)
				(type default)
			)
			(layer "B.SilkS")
		)
		(fp_line
			(start 0.7874 0.4064)
			(end 0.7874 -0.4064)
			(stroke
				(width 0.1524)
				(type default)
			)
			(layer "B.SilkS")
		)
		(fp_line
			(start -0.67945 -0.3048)
			(end -0.67945 0.3048)
			(stroke
				(width 0.1)
				(type default)
			)
			(layer "B.Fab")
		)
		(fp_line
			(start -0.67945 0.3048)
			(end -0.120396 0.3048)
			(stroke
				(width 0.1)
				(type default)
			)
			(layer "B.Fab")
		)
		(fp_line
			(start -0.12065 -0.3048)
			(end -0.67945 -0.3048)
			(stroke
				(width 0.1)
				(type default)
			)
			(layer "B.Fab")
		)
		(fp_line
			(start -0.12065 -0.2794)
			(end -0.12065 -0.3048)
			(stroke
				(width 0.1)
				(type default)
			)
			(layer "B.Fab")
		)
		(fp_line
			(start -0.120396 0.2794)
			(end 0.12065 0.2794)
			(stroke
				(width 0.1)
				(type default)
			)
			(layer "B.Fab")
		)
		(fp_line
			(start -0.120396 0.3048)
			(end -0.120396 0.2794)
			(stroke
				(width 0.1)
				(type default)
			)
			(layer "B.Fab")
		)
		(fp_line
			(start 0.12065 -0.305054)
			(end 0.12065 -0.2794)
			(stroke
				(width 0.1)
				(type default)
			)
			(layer "B.Fab")
		)
		(fp_line
			(start 0.12065 -0.2794)
			(end -0.12065 -0.2794)
			(stroke
				(width 0.1)
				(type default)
			)
			(layer "B.Fab")
		)
		(fp_line
			(start 0.12065 0.2794)
			(end 0.12065 0.3048)
			(stroke
				(width 0.1)
				(type default)
			)
			(layer "B.Fab")
		)
		(fp_line
			(start 0.12065 0.3048)
			(end 0.67945 0.3048)
			(stroke
				(width 0.1)
				(type default)
			)
			(layer "B.Fab")
		)
		(fp_line
			(start 0.67945 -0.305054)
			(end 0.12065 -0.305054)
			(stroke
				(width 0.1)
				(type default)
			)
			(layer "B.Fab")
		)
		(fp_line
			(start 0.67945 0.3048)
			(end 0.67945 -0.305054)
			(stroke
				(width 0.1)
				(type default)
			)
			(layer "B.Fab")
		)
		(pad "1" smd circle
			(at 0.40005 0 180)
			(size 0 0)
			(layers "B.Cu" "B.Mask" "B.Paste")
			(net "PVDDCR_SOC_P1")
		)
		(pad "2" smd circle
			(at -0.40005 0 180)
			(size 0 0)
			(layers "B.Cu" "B.Mask" "B.Paste")
			(net "GND")
		)
	)
	(footprint ""
		(layer "B.Cu")
		(at 198.374 -144.272 -90)
		(property "Reference" "R8103"
			(at 0 0 90)
			(layer "B.SilkS")
			(hide yes)
			(effects
				(font
					(size 1.27 1.27)
				)
				(justify mirror)
			)
		)
		(property "Value" ""
			(at 0 0 90)
			(layer "B.Fab")
			(effects
				(font
					(size 1.27 1.27)
				)
				(justify mirror)
			)
		)
		(duplicate_pad_numbers_are_jumpers no)
		(fp_line
			(start -0.7874 0.4064)
			(end 0.7874 0.4064)
			(stroke
				(width 0.1524)
				(type default)
			)
			(layer "B.SilkS")
		)
		(fp_line
			(start 0.7874 0.4064)
			(end 0.7874 -0.4064)
			(stroke
				(width 0.1524)
				(type default)
			)
			(layer "B.SilkS")
		)
		(fp_line
			(start -0.7874 -0.4064)
			(end -0.7874 0.4064)
			(stroke
				(width 0.1524)
				(type default)
			)
			(layer "B.SilkS")
		)
		(fp_line
			(start 0.7874 -0.4064)
			(end -0.7874 -0.4064)
			(stroke
				(width 0.1524)
				(type default)
			)
			(layer "B.SilkS")
		)
		(fp_line
			(start -0.67945 0.3048)
			(end -0.120396 0.3048)
			(stroke
				(width 0.1)
				(type default)
			)
			(layer "B.Fab")
		)
		(fp_line
			(start -0.120396 0.3048)
			(end -0.120396 0.2794)
			(stroke
				(width 0.1)
				(type default)
			)
			(layer "B.Fab")
		)
		(fp_line
			(start 0.12065 0.3048)
			(end 0.67945 0.3048)
			(stroke
				(width 0.1)
				(type default)
			)
			(layer "B.Fab")
		)
		(fp_line
			(start 0.67945 0.3048)
			(end 0.67945 -0.305054)
			(stroke
				(width 0.1)
				(type default)
			)
			(layer "B.Fab")
		)
		(fp_line
			(start -0.120396 0.2794)
			(end 0.12065 0.2794)
			(stroke
				(width 0.1)
				(type default)
			)
			(layer "B.Fab")
		)
		(fp_line
			(start 0.12065 0.2794)
			(end 0.12065 0.3048)
			(stroke
				(width 0.1)
				(type default)
			)
			(layer "B.Fab")
		)
		(fp_line
			(start -0.12065 -0.2794)
			(end -0.12065 -0.3048)
			(stroke
				(width 0.1)
				(type default)
			)
			(layer "B.Fab")
		)
		(fp_line
			(start 0.12065 -0.2794)
			(end -0.12065 -0.2794)
			(stroke
				(width 0.1)
				(type default)
			)
			(layer "B.Fab")
		)
		(fp_line
			(start -0.67945 -0.3048)
			(end -0.67945 0.3048)
			(stroke
				(width 0.1)
				(type default)
			)
			(layer "B.Fab")
		)
		(fp_line
			(start -0.12065 -0.3048)
			(end -0.67945 -0.3048)
			(stroke
				(width 0.1)
				(type default)
			)
			(layer "B.Fab")
		)
		(fp_line
			(start 0.12065 -0.305054)
			(end 0.12065 -0.2794)
			(stroke
				(width 0.1)
				(type default)
			)
			(layer "B.Fab")
		)
		(fp_line
			(start 0.67945 -0.305054)
			(end 0.12065 -0.305054)
			(stroke
				(width 0.1)
				(type default)
			)
			(layer "B.Fab")
		)
		(pad "1" smd circle
			(at 0.40005 0 90)
			(size 0 0)
			(layers "B.Cu" "B.Mask" "B.Paste")
			(net "P3V3_AUX")
		)
		(pad "2" smd circle
			(at -0.40005 0 90)
			(size 0 0)
			(layers "B.Cu" "B.Mask" "B.Paste")
			(net "FM_AC_PWR_BTN_R_N")
		)
	)
	(footprint ""
		(layer "B.Cu")
		(at 72.416416 -393.242546 180)
		(property "Reference" "R705"
			(at 0 0 0)
			(layer "B.SilkS")
			(hide yes)
			(effects
				(font
					(size 1.27 1.27)
				)
				(justify mirror)
			)
		)
		(property "Value" ""
			(at 0 0 0)
			(layer "B.Fab")
			(effects
				(font
					(size 1.27 1.27)
				)
				(justify mirror)
			)
		)
		(duplicate_pad_numbers_are_jumpers no)
		(fp_line
			(start 1.2954 0.5842)
			(end 1.2954 -0.5842)
			(stroke
				(width 0.1524)
				(type default)
			)
			(layer "B.SilkS")
		)
		(fp_line
			(start 1.2954 -0.5842)
			(end -1.2954 -0.5842)
			(stroke
				(width 0.1524)
				(type default)
			)
			(layer "B.SilkS")
		)
		(fp_line
			(start -1.2954 0.5842)
			(end 1.2954 0.5842)
			(stroke
				(width 0.1524)
				(type default)
			)
			(layer "B.SilkS")
		)
		(fp_line
			(start -1.2954 -0.5842)
			(end -1.2954 0.5842)
			(stroke
				(width 0.1524)
				(type default)
			)
			(layer "B.SilkS")
		)
		(fp_line
			(start 1.1938 0.4064)
			(end 1.1938 -0.406654)
			(stroke
				(width 0.1)
				(type default)
			)
			(layer "B.Fab")
		)
		(fp_line
			(start 1.1938 -0.406654)
			(end 0.8636 -0.406654)
			(stroke
				(width 0.1)
				(type default)
			)
			(layer "B.Fab")
		)
		(fp_line
			(start 0.8636 0.4572)
			(end 0.8636 0.4318)
			(stroke
				(width 0.1)
				(type default)
			)
			(layer "B.Fab")
		)
		(fp_line
			(start 0.8636 0.4318)
			(end 0.8636 0.4064)
			(stroke
				(width 0.1)
				(type default)
			)
			(layer "B.Fab")
		)
		(fp_line
			(start 0.8636 0.4064)
			(end 1.1938 0.4064)
			(stroke
				(width 0.1)
				(type default)
			)
			(layer "B.Fab")
		)
		(fp_line
			(start 0.8636 -0.406654)
			(end 0.8636 -0.4572)
			(stroke
				(width 0.1)
				(type default)
			)
			(layer "B.Fab")
		)
		(fp_line
			(start 0.8636 -0.4572)
			(end -0.8636 -0.4572)
			(stroke
				(width 0.1)
				(type default)
			)
			(layer "B.Fab")
		)
		(fp_line
			(start -0.8636 0.4572)
			(end 0.8636 0.4572)
			(stroke
				(width 0.1)
				(type default)
			)
			(layer "B.Fab")
		)
		(fp_line
			(start -0.8636 0.4064)
			(end -0.8636 0.4572)
			(stroke
				(width 0.1)
				(type default)
			)
			(layer "B.Fab")
		)
		(fp_line
			(start -0.8636 -0.406654)
			(end -1.1938 -0.406654)
			(stroke
				(width 0.1)
				(type default)
			)
			(layer "B.Fab")
		)
		(fp_line
			(start -0.8636 -0.4572)
			(end -0.8636 -0.406654)
			(stroke
				(width 0.1)
				(type default)
			)
			(layer "B.Fab")
		)
		(fp_line
			(start -1.1938 0.4064)
			(end -0.8636 0.4064)
			(stroke
				(width 0.1)
				(type default)
			)
			(layer "B.Fab")
		)
		(fp_line
			(start -1.1938 -0.406654)
			(end -1.1938 0.4064)
			(stroke
				(width 0.1)
				(type default)
			)
			(layer "B.Fab")
		)
		(pad "1" smd rect
			(at 0.7366 0 90)
			(size 0.7112 0.8128)
			(layers "B.Cu" "B.Mask" "B.Paste")
			(net "P0V9_CPU1_RT_2D")
		)
		(pad "2" smd rect
			(at -0.7366 0 90)
			(size 0.7112 0.8128)
			(layers "B.Cu" "B.Mask" "B.Paste")
			(net "P0V9_CPU1_RT1_2A_2D")
		)
	)
	(footprint ""
		(layer "B.Cu")
		(at 12.076684 -112.319308 -90)
		(property "Reference" "U5201"
			(at -3.494532 -1.880616 0)
			(unlocked yes)
			(layer "B.SilkS")
			(effects
				(font
					(size 0.7874 0.5842)
					(thickness 0.1524)
				)
				(justify left mirror)
			)
		)
		(property "Value" ""
			(at 0 0 90)
			(layer "B.Fab")
			(effects
				(font
					(size 1.27 1.27)
				)
				(justify mirror)
			)
		)
		(duplicate_pad_numbers_are_jumpers no)
		(fp_line
			(start -1.2446 1.2446)
			(end -1.2446 0.479044)
			(stroke
				(width 0.1524)
				(type default)
			)
			(layer "B.SilkS")
		)
		(fp_line
			(start 1.2446 1.2446)
			(end -1.2446 1.2446)
			(stroke
				(width 0.1524)
				(type default)
			)
			(layer "B.SilkS")
		)
		(fp_line
			(start 1.2446 0.593344)
			(end 1.2446 1.2446)
			(stroke
				(width 0.1524)
				(type default)
			)
			(layer "B.SilkS")
		)
		(fp_line
			(start -1.2446 -0.506476)
			(end -1.2446 -1.2446)
			(stroke
				(width 0.1524)
				(type default)
			)
			(layer "B.SilkS")
		)
		(fp_line
			(start -1.2446 -1.2446)
			(end 1.2446 -1.2446)
			(stroke
				(width 0.1524)
				(type default)
			)
			(layer "B.SilkS")
		)
		(fp_line
			(start 1.2446 -1.2446)
			(end 1.2446 -0.592836)
			(stroke
				(width 0.1524)
				(type default)
			)
			(layer "B.SilkS")
		)
		(fp_poly
			(pts
				(xy 2.23266 -0.702056) (xy 1.416812 -0.430022) (xy 1.688592 -1.246124)
			)
			(stroke
				(width 0)
				(type default)
			)
			(fill yes)
			(layer "B.SilkS")
		)
		(fp_line
			(start -0.824992 0.824992)
			(end -0.824992 -0.824992)
			(stroke
				(width 0.1)
				(type default)
			)
			(layer "B.Fab")
		)
		(fp_line
			(start 0.824992 0.824992)
			(end -0.824992 0.824992)
			(stroke
				(width 0.1)
				(type default)
			)
			(layer "B.Fab")
		)
		(fp_line
			(start -0.824992 -0.824992)
			(end 0.824992 -0.824992)
			(stroke
				(width 0.1)
				(type default)
			)
			(layer "B.Fab")
		)
		(fp_line
			(start 0.824992 -0.824992)
			(end 0.824992 0.824992)
			(stroke
				(width 0.1)
				(type default)
			)
			(layer "B.Fab")
		)
		(fp_poly
			(pts
				(xy 1.389634 -0.199898) (xy 2.159 0.184658) (xy 2.159 -0.584708)
			)
			(stroke
				(width 0)
				(type default)
			)
			(fill yes)
			(layer "B.Fab")
		)
		(pad "1" smd rect
			(at 0.700024 -0.199898 180)
			(size 0.1778 0.8128)
			(layers "B.Cu" "B.Mask" "B.Paste")
			(net "USB2_HUB_BUF_SWB_R_DN")
		)
		(pad "2" smd rect
			(at 0.700024 0.199898 180)
			(size 0.1778 0.8128)
			(layers "B.Cu" "B.Mask" "B.Paste")
			(net "USB2_HUB_BUF_SWB_R_DP")
		)
		(pad "3" smd rect
			(at 0.599948 0.8001 90)
			(size 0.1778 0.6096)
			(layers "B.Cu" "B.Mask" "B.Paste")
			(net "TP_USB2_TEST")
		)
		(pad "4" smd rect
			(at 0.199898 0.8001 90)
			(size 0.1778 0.6096)
			(layers "B.Cu" "B.Mask" "B.Paste")
			(net "TP_USB2_CD")
		)
		(pad "5" smd rect
			(at -0.199898 0.8001 90)
			(size 0.1778 0.6096)
			(layers "B.Cu" "B.Mask" "B.Paste")
			(net "PD_U5201_RSTN")
		)
		(pad "6" smd rect
			(at -0.599948 0.8001 90)
			(size 0.1778 0.6096)
			(layers "B.Cu" "B.Mask" "B.Paste")
			(net "PD_U5201_EQ")
		)
		(pad "7" smd rect
			(at -0.700024 0.199898 180)
			(size 0.1778 0.8128)
			(layers "B.Cu" "B.Mask" "B.Paste")
			(net "USB2_HUB_BUF_SWB_R_DP")
		)
		(pad "8" smd rect
			(at -0.700024 -0.199898 180)
			(size 0.1778 0.8128)
			(layers "B.Cu" "B.Mask" "B.Paste")
			(net "USB2_HUB_BUF_SWB_R_DN")
		)
		(pad "9" smd rect
			(at -0.599948 -0.8001 90)
			(size 0.1778 0.6096)
			(layers "B.Cu" "B.Mask" "B.Paste")
			(net "TP_USB2_ENA_HS")
		)
		(pad "10" smd rect
			(at -0.199898 -0.8001 90)
			(size 0.1778 0.6096)
			(layers "B.Cu" "B.Mask" "B.Paste")
			(net "GND")
		)
		(pad "11" smd rect
			(at 0.199898 -0.8001 90)
			(size 0.1778 0.6096)
			(layers "B.Cu" "B.Mask" "B.Paste")
			(net "PD_U5201_VREG")
		)
		(pad "12" smd rect
			(at 0.599948 -0.8001 90)
			(size 0.1778 0.6096)
			(layers "B.Cu" "B.Mask" "B.Paste")
			(net "P3V3_AUX")
		)
	)
	(footprint ""
		(layer "B.Cu")
		(at 230.6828 -339.598 180)
		(property "Reference" "R6756"
			(at 0 0 0)
			(layer "B.SilkS")
			(hide yes)
			(effects
				(font
					(size 1.27 1.27)
				)
				(justify mirror)
			)
		)
		(property "Value" ""
			(at 0 0 0)
			(layer "B.Fab")
			(effects
				(font
					(size 1.27 1.27)
				)
				(justify mirror)
			)
		)
		(duplicate_pad_numbers_are_jumpers no)
		(fp_line
			(start 0.32512 0.175006)
			(end 0.32512 -0.175006)
			(stroke
				(width 0.1)
				(type default)
			)
			(layer "B.Fab")
		)
		(fp_line
			(start 0.32512 -0.175006)
			(end -0.32512 -0.175006)
			(stroke
				(width 0.1)
				(type default)
			)
			(layer "B.Fab")
		)
		(fp_line
			(start -0.32512 0.175006)
			(end 0.32512 0.175006)
			(stroke
				(width 0.1)
				(type default)
			)
			(layer "B.Fab")
		)
		(fp_line
			(start -0.32512 -0.175006)
			(end -0.32512 0.175006)
			(stroke
				(width 0.1)
				(type default)
			)
			(layer "B.Fab")
		)
		(pad "1" smd rect
			(at 0.2667 0)
			(size 0.3048 0.381)
			(layers "B.Cu" "B.Mask" "B.Paste")
			(net "SMB_RT_CPU0_P1_SDA")
		)
		(pad "2" smd rect
			(at -0.2667 0 180)
			(size 0.3048 0.381)
			(layers "B.Cu" "B.Mask" "B.Paste")
			(net "SMB_RT_CPU0_P1_R_SDA")
		)
	)
)
